# BASEBOARD_FAB2 (Tioga Pass) — schematic netlist excerpt (pin names and nets, part order shuffled) for the footprints in the layout excerpt that follows; sources: Cadence DE-HDL packaged netlist, KiCad conversion of Wiwynn_Tioga_Pass_MB.brd

R4E6  RES  150.0 1% CHIP  pkg 0402  page 201 : A = SVID_CLK0_CPU0_R ; B = SVID_VCLK_PVCCIN_CPU0
R8B9  RES  113 1% CHIP  pkg 0402  page 115 : A = A_USB2_COMP ; B = GND
C2B2  CAP_A  47UF 4V 20% X5R  pkg 0603V  page 228 : A = PVDDQ_KLM ; B = GND

(kicad_pcb
	(version 20260206)
	(generator "pcbnew")
	(generator_version "10.0")
	(general
		(thickness 1.6)
		(legacy_teardrops no)
	)
	(paper "A4")
	(title_block
		(title "Wiwynn_Tioga_Pass_MB.brd")
		(comment 1 "Tioga Pass / footprints 1106-1108 of 4770")
	)
	(layers
		(0 "F.Cu" signal "TOP")
		(4 "In1.Cu" signal "L2GND")
		(6 "In2.Cu" signal "L3")
		(8 "In3.Cu" signal "L4GND")
		(10 "In4.Cu" signal "L5")
		(12 "In5.Cu" signal "L6GND")
		(14 "In6.Cu" signal "L7VCC")
		(16 "In7.Cu" signal "L8VCC")
		(18 "In8.Cu" signal "L9GND")
		(20 "In9.Cu" signal "L10")
		(22 "In10.Cu" signal "L11GND")
		(24 "In11.Cu" signal "L12")
		(26 "In12.Cu" signal "L13GND")
		(2 "B.Cu" signal "BOTTOM")
		(9 "F.Adhes" user "F.Adhesive")
		(11 "B.Adhes" user "B.Adhesive")
		(13 "F.Paste" user "Package Geometry/Pastemask Top")
		(15 "B.Paste" user "Package Geometry/Pastemask Bottom")
		(5 "F.SilkS" user "Ref Des/Silkscreen Top")
		(7 "B.SilkS" user "Ref Des/Silkscreen Bottom")
		(1 "F.Mask" user "Board Geometry/Soldermask Top")
		(3 "B.Mask" user "Board Geometry/Soldermask Bottom")
		(17 "Dwgs.User" user "User.Drawings")
		(19 "Cmts.User" user "User.Comments")
		(21 "Eco1.User" user "User.Eco1")
		(23 "Eco2.User" user "User.Eco2")
		(25 "Edge.Cuts" user "Board Geometry/Outline")
		(27 "Margin" user)
		(31 "F.CrtYd" user "Package Geometry/Place Bound Top")
		(29 "B.CrtYd" user "Package Geometry/Place Bound Bottom")
		(35 "F.Fab" user "Ref Des/Assembly Top")
		(33 "B.Fab" user "Ref Des/Assembly Bottom")
	)
	(footprint ""
		(layer "F.Cu")
		(at 79.551022 -125.88113 -90)
		(property "Reference" "C2B2"
			(at 0 0 270)
			(layer "F.SilkS")
			(hide yes)
			(effects
				(font
					(size 1.27 1.27)
				)
			)
		)
		(property "Value" ""
			(at 0 0 270)
			(layer "F.Fab")
			(effects
				(font
					(size 1.27 1.27)
				)
			)
		)
		(duplicate_pad_numbers_are_jumpers no)
		(fp_rect
			(start -0.500126 1.598422)
			(end 0.500126 -0.201422)
			(stroke
				(width 0)
				(type default)
			)
			(fill no)
			(layer "F.CrtYd")
		)
		(fp_line
			(start -0.500126 1.598422)
			(end -0.500126 -0.201422)
			(stroke
				(width 0.1)
				(type default)
			)
			(layer "F.Fab")
		)
		(fp_line
			(start 0.500126 1.598422)
			(end -0.500126 1.598422)
			(stroke
				(width 0.1)
				(type default)
			)
			(layer "F.Fab")
		)
		(fp_line
			(start -0.500126 -0.201422)
			(end 0.500126 -0.201422)
			(stroke
				(width 0.1)
				(type default)
			)
			(layer "F.Fab")
		)
		(fp_line
			(start 0.500126 -0.201422)
			(end 0.500126 1.598422)
			(stroke
				(width 0.1)
				(type default)
			)
			(layer "F.Fab")
		)
		(pad "1" smd rect
			(at 0 0 180)
			(size 0.889 0.9906)
			(layers "F.Cu" "F.Mask" "F.Paste")
			(net "PVDDQ_KLM")
		)
		(pad "2" smd rect
			(at 0 1.397 180)
			(size 0.889 0.9906)
			(layers "F.Cu" "F.Mask" "F.Paste")
			(net "GND")
		)
		(zone
			(layer "F.Cu")
			(hatch none 0.5)
			(connect_pads
				(clearance 0)
			)
			(min_thickness 0.25)
			(keepout
				(tracks not_allowed)
				(vias allowed)
				(pads allowed)
				(copperpour not_allowed)
				(footprints allowed)
			)
			(placement
				(enabled no)
				(sheetname "")
			)
			(fill
				(thermal_gap 0.5)
				(thermal_bridge_width 0.5)
				(island_removal_mode 0)
			)
			(polygon
				(pts
					(xy 78.598522 -126.37643) (xy 78.598522 -125.38583) (xy 79.106522 -125.38583) (xy 79.106522 -126.37643)
				)
			)
		)
		(zone
			(layer "F.Cu")
			(hatch none 0.5)
			(connect_pads
				(clearance 0)
			)
			(min_thickness 0.25)
			(keepout
				(tracks allowed)
				(vias not_allowed)
				(pads allowed)
				(copperpour not_allowed)
				(footprints allowed)
			)
			(placement
				(enabled no)
				(sheetname "")
			)
			(fill
				(thermal_gap 0.5)
				(thermal_bridge_width 0.5)
				(island_removal_mode 0)
			)
			(polygon
				(pts
					(xy 78.598522 -126.37643) (xy 78.598522 -125.38583) (xy 79.106522 -125.38583) (xy 79.106522 -126.37643)
				)
			)
		)
	)
	(footprint ""
		(layer "F.Cu")
		(at 183.007 -64.135 180)
		(property "Reference" "R4E6"
			(at 0 0 180)
			(layer "F.SilkS")
			(hide yes)
			(effects
				(font
					(size 1.27 1.27)
				)
			)
		)
		(property "Value" ""
			(at 0 0 180)
			(layer "F.Fab")
			(effects
				(font
					(size 1.27 1.27)
				)
			)
		)
		(duplicate_pad_numbers_are_jumpers no)
		(fp_rect
			(start 0.2794 -0.1016)
			(end -0.2794 0.9906)
			(stroke
				(width 0)
				(type default)
			)
			(fill no)
			(layer "F.CrtYd")
		)
		(fp_line
			(start 0.2794 0.9906)
			(end 0.2794 -0.1016)
			(stroke
				(width 0.1)
				(type default)
			)
			(layer "F.Fab")
		)
		(fp_line
			(start 0.2794 -0.1016)
			(end -0.2794 -0.1016)
			(stroke
				(width 0.1)
				(type default)
			)
			(layer "F.Fab")
		)
		(fp_line
			(start -0.2794 0.9906)
			(end 0.2794 0.9906)
			(stroke
				(width 0.1)
				(type default)
			)
			(layer "F.Fab")
		)
		(fp_line
			(start -0.2794 -0.1016)
			(end -0.2794 0.9906)
			(stroke
				(width 0.1)
				(type default)
			)
			(layer "F.Fab")
		)
		(pad "1" smd rect
			(at 0 0 180)
			(size 0.508 0.508)
			(layers "F.Cu" "F.Mask" "F.Paste")
			(net "SVID_CLK0_CPU0_R")
		)
		(pad "2" smd rect
			(at 0 0.889 180)
			(size 0.508 0.508)
			(layers "F.Cu" "F.Mask" "F.Paste")
			(net "SVID_VCLK_PVCCIN_CPU0")
		)
		(zone
			(layer "F.Cu")
			(hatch none 0.5)
			(connect_pads
				(clearance 0)
			)
			(min_thickness 0.25)
			(keepout
				(tracks not_allowed)
				(vias allowed)
				(pads allowed)
				(copperpour not_allowed)
				(footprints allowed)
			)
			(placement
				(enabled no)
				(sheetname "")
			)
			(fill
				(thermal_gap 0.5)
				(thermal_bridge_width 0.5)
				(island_removal_mode 0)
			)
			(polygon
				(pts
					(xy 182.753 -64.389) (xy 183.261 -64.389) (xy 183.261 -64.77) (xy 182.753 -64.77)
				)
			)
		)
		(zone
			(layer "F.Cu")
			(hatch none 0.5)
			(connect_pads
				(clearance 0)
			)
			(min_thickness 0.25)
			(keepout
				(tracks allowed)
				(vias not_allowed)
				(pads allowed)
				(copperpour not_allowed)
				(footprints allowed)
			)
			(placement
				(enabled no)
				(sheetname "")
			)
			(fill
				(thermal_gap 0.5)
				(thermal_bridge_width 0.5)
				(island_removal_mode 0)
			)
			(polygon
				(pts
					(xy 182.753 -64.389) (xy 183.261 -64.389) (xy 183.261 -64.77) (xy 182.753 -64.77)
				)
			)
		)
	)
	(footprint ""
		(layer "F.Cu")
		(at 403.8854 -124.841 90)
		(property "Reference" "R8B9"
			(at 0 0 90)
			(layer "F.SilkS")
			(hide yes)
			(effects
				(font
					(size 1.27 1.27)
				)
			)
		)
		(property "Value" ""
			(at 0 0 90)
			(layer "F.Fab")
			(effects
				(font
					(size 1.27 1.27)
				)
			)
		)
		(duplicate_pad_numbers_are_jumpers no)
		(fp_poly
			(pts
				(xy -0.2794 -0.1016) (xy 0.2794 -0.1016) (xy 0.2794 0.9906) (xy -0.2794 0.9906)
			)
			(stroke
				(width 0)
				(type default)
			)
			(fill no)
			(layer "F.CrtYd")
		)
		(fp_line
			(start 0.2794 -0.1016)
			(end -0.2794 -0.1016)
			(stroke
				(width 0.1)
				(type default)
			)
			(layer "F.Fab")
		)
		(fp_line
			(start -0.2794 -0.1016)
			(end -0.2794 0.9906)
			(stroke
				(width 0.1)
				(type default)
			)
			(layer "F.Fab")
		)
		(fp_line
			(start 0.2794 0.9906)
			(end 0.2794 -0.1016)
			(stroke
				(width 0.1)
				(type default)
			)
			(layer "F.Fab")
		)
		(fp_line
			(start -0.2794 0.9906)
			(end 0.2794 0.9906)
			(stroke
				(width 0.1)
				(type default)
			)
			(layer "F.Fab")
		)
		(pad "1" smd rect
			(at 0 0 90)
			(size 0.508 0.508)
			(layers "F.Cu" "F.Mask" "F.Paste")
			(net "A_USB2_COMP")
		)
		(pad "2" smd rect
			(at 0 0.889 90)
			(size 0.508 0.508)
			(layers "F.Cu" "F.Mask" "F.Paste")
			(net "GND")
		)
		(zone
			(layer "F.Cu")
			(hatch none 0.5)
			(connect_pads
				(clearance 0)
			)
			(min_thickness 0.25)
			(keepout
				(tracks allowed)
				(vias not_allowed)
				(pads allowed)
				(copperpour not_allowed)
				(footprints allowed)
			)
			(placement
				(enabled no)
				(sheetname "")
			)
			(fill
				(thermal_gap 0.5)
				(thermal_bridge_width 0.5)
				(island_removal_mode 0)
			)
			(polygon
				(pts
					(xy 404.1394 -124.587) (xy 404.1394 -125.095) (xy 404.5204 -125.095) (xy 404.5204 -124.587)
				)
			)
		)
		(zone
			(layer "F.Cu")
			(hatch none 0.5)
			(connect_pads
				(clearance 0)
			)
			(min_thickness 0.25)
			(keepout
				(tracks not_allowed)
				(vias allowed)
				(pads allowed)
				(copperpour not_allowed)
				(footprints allowed)
			)
			(placement
				(enabled no)
				(sheetname "")
			)
			(fill
				(thermal_gap 0.5)
				(thermal_bridge_width 0.5)
				(island_removal_mode 0)
			)
			(polygon
				(pts
					(xy 404.5204 -124.587) (xy 404.5204 -125.095) (xy 404.1394 -125.095) (xy 404.1394 -124.587)
				)
			)
		)
	)
)
